(kicad_pcb
	(version 20260206)
	(generator "pcbnew")
	(generator_version "10.0")
	(general
		(thickness 1.6)
		(legacy_teardrops no)
	)
	(paper "A4")
	(title_block
		(title "03242023_DA0F0TMBIJ0_F0T_Motherboard_J_brd_V01_OCP.brd")
		(comment 1 "Grand Teton / footprints 212-217 of 6105")
	)
	(layers
		(0 "F.Cu" signal "TOP")
		(4 "In1.Cu" signal "GND")
		(6 "In2.Cu" signal "IN1")
		(8 "In3.Cu" signal "GND1")
		(10 "In4.Cu" signal "IN2")
		(12 "In5.Cu" signal "GND2")
		(14 "In6.Cu" signal "IN3")
		(16 "In7.Cu" signal "GND3")
		(18 "In8.Cu" signal "VCC")
		(20 "In9.Cu" signal "VCC1")
		(22 "In10.Cu" signal "GND4")
		(24 "In11.Cu" signal "IN4")
		(26 "In12.Cu" signal "GND5")
		(28 "In13.Cu" signal "IN5")
		(30 "In14.Cu" signal "GND6")
		(32 "In15.Cu" signal "IN6")
		(34 "In16.Cu" signal "GND7")
		(2 "B.Cu" signal "BOTTOM")
		(9 "F.Adhes" user "F.Adhesive")
		(11 "B.Adhes" user "B.Adhesive")
		(13 "F.Paste" user "Package Geometry/Pastemask Top")
		(15 "B.Paste" user "Package Geometry/Pastemask Bottom")
		(5 "F.SilkS" user "Ref Des/Silkscreen Top")
		(7 "B.SilkS" user "Ref Des/Silkscreen Bottom")
		(1 "F.Mask" user "Board Geometry/Soldermask Top")
		(3 "B.Mask" user "Board Geometry/Soldermask Bottom")
		(17 "Dwgs.User" user "User.Drawings")
		(19 "Cmts.User" user "User.Comments")
		(21 "Eco1.User" user "User.Eco1")
		(23 "Eco2.User" user "User.Eco2")
		(25 "Edge.Cuts" user "Board Geometry/Outline")
		(27 "Margin" user)
		(31 "F.CrtYd" user "Package Geometry/Place Bound Top")
		(29 "B.CrtYd" user "Package Geometry/Place Bound Bottom")
		(35 "F.Fab" user "Ref Des/Assembly Top")
		(33 "B.Fab" user "Ref Des/Assembly Bottom")
	)
	(footprint ""
		(layer "F.Cu")
		(at 332.970124 -25.956006 -90)
		(property "Reference" "R1869"
			(at 0 0 270)
			(layer "F.SilkS")
			(hide yes)
			(effects
				(font
					(size 1.27 1.27)
				)
			)
		)
		(property "Value" ""
			(at 0 0 270)
			(layer "F.Fab")
			(effects
				(font
					(size 1.27 1.27)
				)
			)
		)
		(duplicate_pad_numbers_are_jumpers no)
		(fp_line
			(start -0.7874 0.4064)
			(end -0.7874 -0.4064)
			(stroke
				(width 0.1524)
				(type default)
			)
			(layer "F.SilkS")
		)
		(fp_line
			(start 0.7874 0.4064)
			(end -0.7874 0.4064)
			(stroke
				(width 0.1524)
				(type default)
			)
			(layer "F.SilkS")
		)
		(fp_line
			(start -0.7874 -0.4064)
			(end 0.7874 -0.4064)
			(stroke
				(width 0.1524)
				(type default)
			)
			(layer "F.SilkS")
		)
		(fp_line
			(start 0.7874 -0.4064)
			(end 0.7874 0.4064)
			(stroke
				(width 0.1524)
				(type default)
			)
			(layer "F.SilkS")
		)
		(fp_line
			(start -0.67945 0.3048)
			(end -0.67945 -0.305054)
			(stroke
				(width 0.1)
				(type default)
			)
			(layer "F.Fab")
		)
		(fp_line
			(start -0.12065 0.3048)
			(end -0.67945 0.3048)
			(stroke
				(width 0.1)
				(type default)
			)
			(layer "F.Fab")
		)
		(fp_line
			(start 0.120396 0.3048)
			(end 0.120396 0.2794)
			(stroke
				(width 0.1)
				(type default)
			)
			(layer "F.Fab")
		)
		(fp_line
			(start 0.67945 0.3048)
			(end 0.120396 0.3048)
			(stroke
				(width 0.1)
				(type default)
			)
			(layer "F.Fab")
		)
		(fp_line
			(start -0.12065 0.2794)
			(end -0.12065 0.3048)
			(stroke
				(width 0.1)
				(type default)
			)
			(layer "F.Fab")
		)
		(fp_line
			(start 0.120396 0.2794)
			(end -0.12065 0.2794)
			(stroke
				(width 0.1)
				(type default)
			)
			(layer "F.Fab")
		)
		(fp_line
			(start -0.12065 -0.2794)
			(end 0.12065 -0.2794)
			(stroke
				(width 0.1)
				(type default)
			)
			(layer "F.Fab")
		)
		(fp_line
			(start 0.12065 -0.2794)
			(end 0.12065 -0.3048)
			(stroke
				(width 0.1)
				(type default)
			)
			(layer "F.Fab")
		)
		(fp_line
			(start 0.12065 -0.3048)
			(end 0.67945 -0.3048)
			(stroke
				(width 0.1)
				(type default)
			)
			(layer "F.Fab")
		)
		(fp_line
			(start 0.67945 -0.3048)
			(end 0.67945 0.3048)
			(stroke
				(width 0.1)
				(type default)
			)
			(layer "F.Fab")
		)
		(fp_line
			(start -0.67945 -0.305054)
			(end -0.12065 -0.305054)
			(stroke
				(width 0.1)
				(type default)
			)
			(layer "F.Fab")
		)
		(fp_line
			(start -0.12065 -0.305054)
			(end -0.12065 -0.2794)
			(stroke
				(width 0.1)
				(type default)
			)
			(layer "F.Fab")
		)
		(pad "1" smd circle
			(at -0.40005 0 270)
			(size 0 0)
			(layers "F.Cu" "F.Mask" "F.Paste")
			(net "ESPI_LAD0_DATA_IO2")
		)
		(pad "2" smd circle
			(at 0.40005 0 270)
			(size 0 0)
			(layers "F.Cu" "F.Mask" "F.Paste")
			(net "ESPI_LPC_LAD0_IO2")
		)
	)
	(footprint ""
		(layer "F.Cu")
		(at 92.98305 -354.314252 -90)
		(property "Reference" "PL32"
			(at -7.407148 1.378712 0)
			(unlocked yes)
			(layer "F.SilkS")
			(effects
				(font
					(size 0.7874 0.5842)
					(thickness 0.1524)
				)
				(justify left)
			)
		)
		(property "Value" ""
			(at 0 0 270)
			(layer "F.Fab")
			(effects
				(font
					(size 1.27 1.27)
				)
			)
		)
		(duplicate_pad_numbers_are_jumpers no)
		(fp_line
			(start -4.99999 4.150106)
			(end 4.99999 4.150106)
			(stroke
				(width 0.1524)
				(type default)
			)
			(layer "F.SilkS")
		)
		(fp_line
			(start 4.99999 4.150106)
			(end 4.99999 2.4892)
			(stroke
				(width 0.1524)
				(type default)
			)
			(layer "F.SilkS")
		)
		(fp_line
			(start -4.99999 2.4892)
			(end -4.99999 4.150106)
			(stroke
				(width 0.1524)
				(type default)
			)
			(layer "F.SilkS")
		)
		(fp_line
			(start 4.99999 -2.4892)
			(end 4.99999 -4.150106)
			(stroke
				(width 0.1524)
				(type default)
			)
			(layer "F.SilkS")
		)
		(fp_line
			(start -4.99999 -4.150106)
			(end -4.99999 -2.4892)
			(stroke
				(width 0.1524)
				(type default)
			)
			(layer "F.SilkS")
		)
		(fp_line
			(start 4.99999 -4.150106)
			(end -4.99999 -4.150106)
			(stroke
				(width 0.1524)
				(type default)
			)
			(layer "F.SilkS")
		)
		(fp_line
			(start -4.99999 4.150106)
			(end 4.99999 4.150106)
			(stroke
				(width 0.1)
				(type default)
			)
			(layer "F.Fab")
		)
		(fp_line
			(start 4.99999 4.150106)
			(end 4.99999 -4.150106)
			(stroke
				(width 0.1)
				(type default)
			)
			(layer "F.Fab")
		)
		(fp_line
			(start -4.99999 -4.150106)
			(end -4.99999 4.150106)
			(stroke
				(width 0.1)
				(type default)
			)
			(layer "F.Fab")
		)
		(fp_line
			(start 4.99999 -4.150106)
			(end -4.99999 -4.150106)
			(stroke
				(width 0.1)
				(type default)
			)
			(layer "F.Fab")
		)
		(pad "1" smd rect
			(at -4.174998 0 270)
			(size 2.159 4.699)
			(layers "F.Cu" "F.Mask" "F.Paste")
			(net "P12V_AUX")
		)
		(pad "2" smd rect
			(at 4.174998 0 270)
			(size 2.159 4.699)
			(layers "F.Cu" "F.Mask" "F.Paste")
			(net "SW_P12V_PVCCIN_CPU1_FLT")
		)
	)
	(footprint ""
		(layer "F.Cu")
		(at 448.61988 -95.872808 180)
		(property "Reference" "R3587"
			(at 0 0 180)
			(layer "F.SilkS")
			(hide yes)
			(effects
				(font
					(size 1.27 1.27)
				)
			)
		)
		(property "Value" ""
			(at 0 0 180)
			(layer "F.Fab")
			(effects
				(font
					(size 1.27 1.27)
				)
			)
		)
		(duplicate_pad_numbers_are_jumpers no)
		(fp_line
			(start 0.7874 0.4064)
			(end -0.7874 0.4064)
			(stroke
				(width 0.1524)
				(type default)
			)
			(layer "F.SilkS")
		)
		(fp_line
			(start 0.7874 -0.4064)
			(end 0.7874 0.4064)
			(stroke
				(width 0.1524)
				(type default)
			)
			(layer "F.SilkS")
		)
		(fp_line
			(start -0.7874 0.4064)
			(end -0.7874 -0.4064)
			(stroke
				(width 0.1524)
				(type default)
			)
			(layer "F.SilkS")
		)
		(fp_line
			(start -0.7874 -0.4064)
			(end 0.7874 -0.4064)
			(stroke
				(width 0.1524)
				(type default)
			)
			(layer "F.SilkS")
		)
		(fp_line
			(start 0.67945 0.3048)
			(end 0.120396 0.3048)
			(stroke
				(width 0.1)
				(type default)
			)
			(layer "F.Fab")
		)
		(fp_line
			(start 0.67945 -0.3048)
			(end 0.67945 0.3048)
			(stroke
				(width 0.1)
				(type default)
			)
			(layer "F.Fab")
		)
		(fp_line
			(start 0.12065 -0.2794)
			(end 0.12065 -0.3048)
			(stroke
				(width 0.1)
				(type default)
			)
			(layer "F.Fab")
		)
		(fp_line
			(start 0.12065 -0.3048)
			(end 0.67945 -0.3048)
			(stroke
				(width 0.1)
				(type default)
			)
			(layer "F.Fab")
		)
		(fp_line
			(start 0.120396 0.3048)
			(end 0.120396 0.2794)
			(stroke
				(width 0.1)
				(type default)
			)
			(layer "F.Fab")
		)
		(fp_line
			(start 0.120396 0.2794)
			(end -0.12065 0.2794)
			(stroke
				(width 0.1)
				(type default)
			)
			(layer "F.Fab")
		)
		(fp_line
			(start -0.12065 0.3048)
			(end -0.67945 0.3048)
			(stroke
				(width 0.1)
				(type default)
			)
			(layer "F.Fab")
		)
		(fp_line
			(start -0.12065 0.2794)
			(end -0.12065 0.3048)
			(stroke
				(width 0.1)
				(type default)
			)
			(layer "F.Fab")
		)
		(fp_line
			(start -0.12065 -0.2794)
			(end 0.12065 -0.2794)
			(stroke
				(width 0.1)
				(type default)
			)
			(layer "F.Fab")
		)
		(fp_line
			(start -0.12065 -0.305054)
			(end -0.12065 -0.2794)
			(stroke
				(width 0.1)
				(type default)
			)
			(layer "F.Fab")
		)
		(fp_line
			(start -0.67945 0.3048)
			(end -0.67945 -0.305054)
			(stroke
				(width 0.1)
				(type default)
			)
			(layer "F.Fab")
		)
		(fp_line
			(start -0.67945 -0.305054)
			(end -0.12065 -0.305054)
			(stroke
				(width 0.1)
				(type default)
			)
			(layer "F.Fab")
		)
		(pad "1" smd circle
			(at -0.40005 0 180)
			(size 0 0)
			(layers "F.Cu" "F.Mask" "F.Paste")
			(net "SMB_INA230_3V3AUX_SDA")
		)
		(pad "2" smd circle
			(at 0.40005 0 180)
			(size 0 0)
			(layers "F.Cu" "F.Mask" "F.Paste")
			(net "SMB_INA230_1_3V3AUX_SDA_R")
		)
	)
	(footprint ""
		(layer "F.Cu")
		(at 201.73188 -108.422948 -90)
		(property "Reference" "R365"
			(at 0 0 270)
			(layer "F.SilkS")
			(hide yes)
			(effects
				(font
					(size 1.27 1.27)
				)
			)
		)
		(property "Value" ""
			(at 0 0 270)
			(layer "F.Fab")
			(effects
				(font
					(size 1.27 1.27)
				)
			)
		)
		(duplicate_pad_numbers_are_jumpers no)
		(fp_line
			(start -0.7874 0.4064)
			(end -0.7874 -0.4064)
			(stroke
				(width 0.1524)
				(type default)
			)
			(layer "F.SilkS")
		)
		(fp_line
			(start 0.7874 0.4064)
			(end -0.7874 0.4064)
			(stroke
				(width 0.1524)
				(type default)
			)
			(layer "F.SilkS")
		)
		(fp_line
			(start -0.7874 -0.4064)
			(end 0.7874 -0.4064)
			(stroke
				(width 0.1524)
				(type default)
			)
			(layer "F.SilkS")
		)
		(fp_line
			(start 0.7874 -0.4064)
			(end 0.7874 0.4064)
			(stroke
				(width 0.1524)
				(type default)
			)
			(layer "F.SilkS")
		)
		(fp_line
			(start -0.67945 0.3048)
			(end -0.67945 -0.305054)
			(stroke
				(width 0.1)
				(type default)
			)
			(layer "F.Fab")
		)
		(fp_line
			(start -0.12065 0.3048)
			(end -0.67945 0.3048)
			(stroke
				(width 0.1)
				(type default)
			)
			(layer "F.Fab")
		)
		(fp_line
			(start 0.120396 0.3048)
			(end 0.120396 0.2794)
			(stroke
				(width 0.1)
				(type default)
			)
			(layer "F.Fab")
		)
		(fp_line
			(start 0.67945 0.3048)
			(end 0.120396 0.3048)
			(stroke
				(width 0.1)
				(type default)
			)
			(layer "F.Fab")
		)
		(fp_line
			(start -0.12065 0.2794)
			(end -0.12065 0.3048)
			(stroke
				(width 0.1)
				(type default)
			)
			(layer "F.Fab")
		)
		(fp_line
			(start 0.120396 0.2794)
			(end -0.12065 0.2794)
			(stroke
				(width 0.1)
				(type default)
			)
			(layer "F.Fab")
		)
		(fp_line
			(start -0.12065 -0.2794)
			(end 0.12065 -0.2794)
			(stroke
				(width 0.1)
				(type default)
			)
			(layer "F.Fab")
		)
		(fp_line
			(start 0.12065 -0.2794)
			(end 0.12065 -0.3048)
			(stroke
				(width 0.1)
				(type default)
			)
			(layer "F.Fab")
		)
		(fp_line
			(start 0.12065 -0.3048)
			(end 0.67945 -0.3048)
			(stroke
				(width 0.1)
				(type default)
			)
			(layer "F.Fab")
		)
		(fp_line
			(start 0.67945 -0.3048)
			(end 0.67945 0.3048)
			(stroke
				(width 0.1)
				(type default)
			)
			(layer "F.Fab")
		)
		(fp_line
			(start -0.67945 -0.305054)
			(end -0.12065 -0.305054)
			(stroke
				(width 0.1)
				(type default)
			)
			(layer "F.Fab")
		)
		(fp_line
			(start -0.12065 -0.305054)
			(end -0.12065 -0.2794)
			(stroke
				(width 0.1)
				(type default)
			)
			(layer "F.Fab")
		)
		(pad "1" smd circle
			(at -0.40005 0 270)
			(size 0 0)
			(layers "F.Cu" "F.Mask" "F.Paste")
			(net "FM_CPU_RMCA_CATERR_LVT3_R_N")
		)
		(pad "2" smd circle
			(at 0.40005 0 270)
			(size 0 0)
			(layers "F.Cu" "F.Mask" "F.Paste")
			(net "CPU_RMCA_CATERR_LVT3_N")
		)
	)
	(footprint ""
		(layer "F.Cu")
		(at 366.629188 -355.651816 180)
		(property "Reference" "C1301"
			(at 0 0 180)
			(layer "F.SilkS")
			(hide yes)
			(effects
				(font
					(size 1.27 1.27)
				)
			)
		)
		(property "Value" ""
			(at 0 0 180)
			(layer "F.Fab")
			(effects
				(font
					(size 1.27 1.27)
				)
			)
		)
		(duplicate_pad_numbers_are_jumpers no)
		(fp_line
			(start 0.7874 0.4064)
			(end -0.7874 0.4064)
			(stroke
				(width 0.1524)
				(type default)
			)
			(layer "F.SilkS")
		)
		(fp_line
			(start 0.7874 -0.4064)
			(end 0.7874 0.4064)
			(stroke
				(width 0.1524)
				(type default)
			)
			(layer "F.SilkS")
		)
		(fp_line
			(start -0.7874 0.4064)
			(end -0.7874 -0.4064)
			(stroke
				(width 0.1524)
				(type default)
			)
			(layer "F.SilkS")
		)
		(fp_line
			(start -0.7874 -0.4064)
			(end 0.7874 -0.4064)
			(stroke
				(width 0.1524)
				(type default)
			)
			(layer "F.SilkS")
		)
		(fp_line
			(start 0.67945 0.3048)
			(end 0.120396 0.3048)
			(stroke
				(width 0.1)
				(type default)
			)
			(layer "F.Fab")
		)
		(fp_line
			(start 0.67945 -0.3048)
			(end 0.67945 0.3048)
			(stroke
				(width 0.1)
				(type default)
			)
			(layer "F.Fab")
		)
		(fp_line
			(start 0.12065 -0.2794)
			(end 0.12065 -0.3048)
			(stroke
				(width 0.1)
				(type default)
			)
			(layer "F.Fab")
		)
		(fp_line
			(start 0.12065 -0.3048)
			(end 0.67945 -0.3048)
			(stroke
				(width 0.1)
				(type default)
			)
			(layer "F.Fab")
		)
		(fp_line
			(start 0.120396 0.3048)
			(end 0.120396 0.2794)
			(stroke
				(width 0.1)
				(type default)
			)
			(layer "F.Fab")
		)
		(fp_line
			(start 0.120396 0.2794)
			(end -0.12065 0.2794)
			(stroke
				(width 0.1)
				(type default)
			)
			(layer "F.Fab")
		)
		(fp_line
			(start -0.12065 0.3048)
			(end -0.67945 0.3048)
			(stroke
				(width 0.1)
				(type default)
			)
			(layer "F.Fab")
		)
		(fp_line
			(start -0.12065 0.2794)
			(end -0.12065 0.3048)
			(stroke
				(width 0.1)
				(type default)
			)
			(layer "F.Fab")
		)
		(fp_line
			(start -0.12065 -0.2794)
			(end 0.12065 -0.2794)
			(stroke
				(width 0.1)
				(type default)
			)
			(layer "F.Fab")
		)
		(fp_line
			(start -0.12065 -0.305054)
			(end -0.12065 -0.2794)
			(stroke
				(width 0.1)
				(type default)
			)
			(layer "F.Fab")
		)
		(fp_line
			(start -0.67945 0.3048)
			(end -0.67945 -0.305054)
			(stroke
				(width 0.1)
				(type default)
			)
			(layer "F.Fab")
		)
		(fp_line
			(start -0.67945 -0.305054)
			(end -0.12065 -0.305054)
			(stroke
				(width 0.1)
				(type default)
			)
			(layer "F.Fab")
		)
		(pad "1" smd circle
			(at -0.40005 0 180)
			(size 0 0)
			(layers "F.Cu" "F.Mask" "F.Paste")
			(net "PWRGD_PVPP_HBM_CPU0_R")
		)
		(pad "2" smd circle
			(at 0.40005 0 180)
			(size 0 0)
			(layers "F.Cu" "F.Mask" "F.Paste")
			(net "GND")
		)
	)
	(footprint ""
		(layer "F.Cu")
		(at 95.94596 -31.575248)
		(property "Reference" "R3228"
			(at 0 0 0)
			(layer "F.SilkS")
			(hide yes)
			(effects
				(font
					(size 1.27 1.27)
				)
			)
		)
		(property "Value" ""
			(at 0 0 0)
			(layer "F.Fab")
			(effects
				(font
					(size 1.27 1.27)
				)
			)
		)
		(duplicate_pad_numbers_are_jumpers no)
		(fp_line
			(start -0.7874 -0.4064)
			(end 0.7874 -0.4064)
			(stroke
				(width 0.1524)
				(type default)
			)
			(layer "F.SilkS")
		)
		(fp_line
			(start -0.7874 0.4064)
			(end -0.7874 -0.4064)
			(stroke
				(width 0.1524)
				(type default)
			)
			(layer "F.SilkS")
		)
		(fp_line
			(start 0.7874 -0.4064)
			(end 0.7874 0.4064)
			(stroke
				(width 0.1524)
				(type default)
			)
			(layer "F.SilkS")
		)
		(fp_line
			(start 0.7874 0.4064)
			(end -0.7874 0.4064)
			(stroke
				(width 0.1524)
				(type default)
			)
			(layer "F.SilkS")
		)
		(fp_line
			(start -0.67945 -0.305054)
			(end -0.12065 -0.305054)
			(stroke
				(width 0.1)
				(type default)
			)
			(layer "F.Fab")
		)
		(fp_line
			(start -0.67945 0.3048)
			(end -0.67945 -0.305054)
			(stroke
				(width 0.1)
				(type default)
			)
			(layer "F.Fab")
		)
		(fp_line
			(start -0.12065 -0.305054)
			(end -0.12065 -0.2794)
			(stroke
				(width 0.1)
				(type default)
			)
			(layer "F.Fab")
		)
		(fp_line
			(start -0.12065 -0.2794)
			(end 0.12065 -0.2794)
			(stroke
				(width 0.1)
				(type default)
			)
			(layer "F.Fab")
		)
		(fp_line
			(start -0.12065 0.2794)
			(end -0.12065 0.3048)
			(stroke
				(width 0.1)
				(type default)
			)
			(layer "F.Fab")
		)
		(fp_line
			(start -0.12065 0.3048)
			(end -0.67945 0.3048)
			(stroke
				(width 0.1)
				(type default)
			)
			(layer "F.Fab")
		)
		(fp_line
			(start 0.120396 0.2794)
			(end -0.12065 0.2794)
			(stroke
				(width 0.1)
				(type default)
			)
			(layer "F.Fab")
		)
		(fp_line
			(start 0.120396 0.3048)
			(end 0.120396 0.2794)
			(stroke
				(width 0.1)
				(type default)
			)
			(layer "F.Fab")
		)
		(fp_line
			(start 0.12065 -0.3048)
			(end 0.67945 -0.3048)
			(stroke
				(width 0.1)
				(type default)
			)
			(layer "F.Fab")
		)
		(fp_line
			(start 0.12065 -0.2794)
			(end 0.12065 -0.3048)
			(stroke
				(width 0.1)
				(type default)
			)
			(layer "F.Fab")
		)
		(fp_line
			(start 0.67945 -0.3048)
			(end 0.67945 0.3048)
			(stroke
				(width 0.1)
				(type default)
			)
			(layer "F.Fab")
		)
		(fp_line
			(start 0.67945 0.3048)
			(end 0.120396 0.3048)
			(stroke
				(width 0.1)
				(type default)
			)
			(layer "F.Fab")
		)
		(pad "1" smd circle
			(at -0.40005 0)
			(size 0 0)
			(layers "F.Cu" "F.Mask" "F.Paste")
			(net "SMB_OCP_V3_2_3V3AUX_BUF_R_SCL")
		)
		(pad "2" smd circle
			(at 0.40005 0)
			(size 0 0)
			(layers "F.Cu" "F.Mask" "F.Paste")
			(net "SMB_OCP_V3_2_3V3AUX_BUF_SCL")
		)
	)
)
